(kicad_pcb
	(version 20260206)
	(generator "pcbnew")
	(generator_version "10.0")
	(general
		(thickness 1.6)
		(legacy_teardrops no)
	)
	(paper "A4")
	(title_block
		(title "04192023_DAF0TMB3IC0_F0TG_MB_C_brd_V02_OCP.brd")
		(comment 1 "Grand Teton / footprints 5745-5752 of 8354")
	)
	(layers
		(0 "F.Cu" signal "TOP")
		(4 "In1.Cu" signal "GND")
		(6 "In2.Cu" signal "IN1")
		(8 "In3.Cu" signal "GND1")
		(10 "In4.Cu" signal "IN2")
		(12 "In5.Cu" signal "GND2")
		(14 "In6.Cu" signal "IN3")
		(16 "In7.Cu" signal "GND3")
		(18 "In8.Cu" signal "VCC")
		(20 "In9.Cu" signal "VCC1")
		(22 "In10.Cu" signal "GND4")
		(24 "In11.Cu" signal "IN4")
		(26 "In12.Cu" signal "GND5")
		(28 "In13.Cu" signal "IN5")
		(30 "In14.Cu" signal "GND6")
		(32 "In15.Cu" signal "IN6")
		(34 "In16.Cu" signal "GND7")
		(2 "B.Cu" signal "BOTTOM")
		(9 "F.Adhes" user "F.Adhesive")
		(11 "B.Adhes" user "B.Adhesive")
		(13 "F.Paste" user "Package Geometry/Pastemask Top")
		(15 "B.Paste" user "Package Geometry/Pastemask Bottom")
		(5 "F.SilkS" user "Ref Des/Silkscreen Top")
		(7 "B.SilkS" user "Ref Des/Silkscreen Bottom")
		(1 "F.Mask" user "Board Geometry/Soldermask Top")
		(3 "B.Mask" user "Board Geometry/Soldermask Bottom")
		(17 "Dwgs.User" user "User.Drawings")
		(19 "Cmts.User" user "User.Comments")
		(21 "Eco1.User" user "User.Eco1")
		(23 "Eco2.User" user "User.Eco2")
		(25 "Edge.Cuts" user "Board Geometry/Outline")
		(27 "Margin" user)
		(31 "F.CrtYd" user "Package Geometry/Place Bound Top")
		(29 "B.CrtYd" user "Package Geometry/Place Bound Bottom")
		(35 "F.Fab" user "Ref Des/Assembly Top")
		(33 "B.Fab" user "Ref Des/Assembly Bottom")
	)
	(footprint ""
		(layer "B.Cu")
		(at 233.807 -334.01 180)
		(property "Reference" "R1067"
			(at 0 0 0)
			(layer "B.SilkS")
			(hide yes)
			(effects
				(font
					(size 1.27 1.27)
				)
				(justify mirror)
			)
		)
		(property "Value" ""
			(at 0 0 0)
			(layer "B.Fab")
			(effects
				(font
					(size 1.27 1.27)
				)
				(justify mirror)
			)
		)
		(duplicate_pad_numbers_are_jumpers no)
		(fp_line
			(start 0.32512 0.175006)
			(end 0.32512 -0.175006)
			(stroke
				(width 0.1)
				(type default)
			)
			(layer "B.Fab")
		)
		(fp_line
			(start 0.32512 -0.175006)
			(end -0.32512 -0.175006)
			(stroke
				(width 0.1)
				(type default)
			)
			(layer "B.Fab")
		)
		(fp_line
			(start -0.32512 0.175006)
			(end 0.32512 0.175006)
			(stroke
				(width 0.1)
				(type default)
			)
			(layer "B.Fab")
		)
		(fp_line
			(start -0.32512 -0.175006)
			(end -0.32512 0.175006)
			(stroke
				(width 0.1)
				(type default)
			)
			(layer "B.Fab")
		)
		(pad "1" smd rect
			(at 0.2667 0)
			(size 0.3048 0.381)
			(layers "B.Cu" "B.Mask" "B.Paste")
			(net "SMB_RT_CPU0_P2_R_SCL")
		)
		(pad "2" smd rect
			(at -0.2667 0 180)
			(size 0.3048 0.381)
			(layers "B.Cu" "B.Mask" "B.Paste")
			(net "SMB_RT_CPU0_P2_R2_SCL")
		)
	)
	(footprint ""
		(layer "B.Cu")
		(at 396.611856 -173.394878 90)
		(property "Reference" "PC587_1"
			(at 0 0 90)
			(layer "B.SilkS")
			(hide yes)
			(effects
				(font
					(size 1.27 1.27)
				)
				(justify mirror)
			)
		)
		(property "Value" ""
			(at 0 0 90)
			(layer "B.Fab")
			(effects
				(font
					(size 1.27 1.27)
				)
				(justify mirror)
			)
		)
		(duplicate_pad_numbers_are_jumpers no)
		(fp_line
			(start 1.524 -0.762)
			(end -1.524 -0.762)
			(stroke
				(width 0.1524)
				(type default)
			)
			(layer "B.SilkS")
		)
		(fp_line
			(start -1.524 -0.762)
			(end -1.524 0.762)
			(stroke
				(width 0.1524)
				(type default)
			)
			(layer "B.SilkS")
		)
		(fp_line
			(start 1.524 0.762)
			(end 1.524 -0.762)
			(stroke
				(width 0.1524)
				(type default)
			)
			(layer "B.SilkS")
		)
		(fp_line
			(start -1.524 0.762)
			(end 1.524 0.762)
			(stroke
				(width 0.1524)
				(type default)
			)
			(layer "B.SilkS")
		)
		(fp_line
			(start 1.1049 -0.724916)
			(end 1.1049 0.724916)
			(stroke
				(width 0.1)
				(type default)
			)
			(layer "B.Fab")
		)
		(fp_line
			(start -1.1049 -0.724916)
			(end 1.1049 -0.724916)
			(stroke
				(width 0.1)
				(type default)
			)
			(layer "B.Fab")
		)
		(fp_line
			(start 1.1049 0.724916)
			(end -1.1049 0.724916)
			(stroke
				(width 0.1)
				(type default)
			)
			(layer "B.Fab")
		)
		(fp_line
			(start -1.1049 0.724916)
			(end -1.1049 -0.724916)
			(stroke
				(width 0.1)
				(type default)
			)
			(layer "B.Fab")
		)
		(pad "1" smd rect
			(at 0.889 0 90)
			(size 1.016 1.27)
			(layers "B.Cu" "B.Mask" "B.Paste")
			(net "SW_P12V_AUX_PVDDCR_SOC_P0_FLT")
		)
		(pad "2" smd rect
			(at -0.889 0 90)
			(size 1.016 1.27)
			(layers "B.Cu" "B.Mask" "B.Paste")
			(net "GND")
		)
	)
	(footprint ""
		(layer "B.Cu")
		(at 435.050946 -26.886408 90)
		(property "Reference" "R1897"
			(at 0 0 90)
			(layer "B.SilkS")
			(hide yes)
			(effects
				(font
					(size 1.27 1.27)
				)
				(justify mirror)
			)
		)
		(property "Value" ""
			(at 0 0 90)
			(layer "B.Fab")
			(effects
				(font
					(size 1.27 1.27)
				)
				(justify mirror)
			)
		)
		(duplicate_pad_numbers_are_jumpers no)
		(fp_line
			(start 0.7874 -0.4064)
			(end -0.7874 -0.4064)
			(stroke
				(width 0.1524)
				(type default)
			)
			(layer "B.SilkS")
		)
		(fp_line
			(start -0.7874 -0.4064)
			(end -0.7874 0.4064)
			(stroke
				(width 0.1524)
				(type default)
			)
			(layer "B.SilkS")
		)
		(fp_line
			(start 0.7874 0.4064)
			(end 0.7874 -0.4064)
			(stroke
				(width 0.1524)
				(type default)
			)
			(layer "B.SilkS")
		)
		(fp_line
			(start -0.7874 0.4064)
			(end 0.7874 0.4064)
			(stroke
				(width 0.1524)
				(type default)
			)
			(layer "B.SilkS")
		)
		(fp_line
			(start 0.67945 -0.305054)
			(end 0.12065 -0.305054)
			(stroke
				(width 0.1)
				(type default)
			)
			(layer "B.Fab")
		)
		(fp_line
			(start 0.12065 -0.305054)
			(end 0.12065 -0.2794)
			(stroke
				(width 0.1)
				(type default)
			)
			(layer "B.Fab")
		)
		(fp_line
			(start -0.12065 -0.3048)
			(end -0.67945 -0.3048)
			(stroke
				(width 0.1)
				(type default)
			)
			(layer "B.Fab")
		)
		(fp_line
			(start -0.67945 -0.3048)
			(end -0.67945 0.3048)
			(stroke
				(width 0.1)
				(type default)
			)
			(layer "B.Fab")
		)
		(fp_line
			(start 0.12065 -0.2794)
			(end -0.12065 -0.2794)
			(stroke
				(width 0.1)
				(type default)
			)
			(layer "B.Fab")
		)
		(fp_line
			(start -0.12065 -0.2794)
			(end -0.12065 -0.3048)
			(stroke
				(width 0.1)
				(type default)
			)
			(layer "B.Fab")
		)
		(fp_line
			(start 0.12065 0.2794)
			(end 0.12065 0.3048)
			(stroke
				(width 0.1)
				(type default)
			)
			(layer "B.Fab")
		)
		(fp_line
			(start -0.120396 0.2794)
			(end 0.12065 0.2794)
			(stroke
				(width 0.1)
				(type default)
			)
			(layer "B.Fab")
		)
		(fp_line
			(start 0.67945 0.3048)
			(end 0.67945 -0.305054)
			(stroke
				(width 0.1)
				(type default)
			)
			(layer "B.Fab")
		)
		(fp_line
			(start 0.12065 0.3048)
			(end 0.67945 0.3048)
			(stroke
				(width 0.1)
				(type default)
			)
			(layer "B.Fab")
		)
		(fp_line
			(start -0.120396 0.3048)
			(end -0.120396 0.2794)
			(stroke
				(width 0.1)
				(type default)
			)
			(layer "B.Fab")
		)
		(fp_line
			(start -0.67945 0.3048)
			(end -0.120396 0.3048)
			(stroke
				(width 0.1)
				(type default)
			)
			(layer "B.Fab")
		)
		(pad "1" smd circle
			(at 0.40005 0 270)
			(size 0 0)
			(layers "B.Cu" "B.Mask" "B.Paste")
			(net "OCP_SFF_ISO_BIF1_EN")
		)
		(pad "2" smd circle
			(at -0.40005 0 270)
			(size 0 0)
			(layers "B.Cu" "B.Mask" "B.Paste")
			(net "GND")
		)
	)
	(footprint ""
		(layer "B.Cu")
		(at 106.466386 -267.529564)
		(property "Reference" "C2403"
			(at 0 0 0)
			(layer "B.SilkS")
			(hide yes)
			(effects
				(font
					(size 1.27 1.27)
				)
				(justify mirror)
			)
		)
		(property "Value" ""
			(at 0 0 0)
			(layer "B.Fab")
			(effects
				(font
					(size 1.27 1.27)
				)
				(justify mirror)
			)
		)
		(duplicate_pad_numbers_are_jumpers no)
		(fp_line
			(start -0.7874 -0.4064)
			(end -0.7874 0.4064)
			(stroke
				(width 0.1524)
				(type default)
			)
			(layer "B.SilkS")
		)
		(fp_line
			(start -0.7874 0.4064)
			(end 0.7874 0.4064)
			(stroke
				(width 0.1524)
				(type default)
			)
			(layer "B.SilkS")
		)
		(fp_line
			(start 0.7874 -0.4064)
			(end -0.7874 -0.4064)
			(stroke
				(width 0.1524)
				(type default)
			)
			(layer "B.SilkS")
		)
		(fp_line
			(start 0.7874 0.4064)
			(end 0.7874 -0.4064)
			(stroke
				(width 0.1524)
				(type default)
			)
			(layer "B.SilkS")
		)
		(fp_line
			(start -0.67945 -0.3048)
			(end -0.67945 0.3048)
			(stroke
				(width 0.1)
				(type default)
			)
			(layer "B.Fab")
		)
		(fp_line
			(start -0.67945 0.3048)
			(end -0.120396 0.3048)
			(stroke
				(width 0.1)
				(type default)
			)
			(layer "B.Fab")
		)
		(fp_line
			(start -0.12065 -0.3048)
			(end -0.67945 -0.3048)
			(stroke
				(width 0.1)
				(type default)
			)
			(layer "B.Fab")
		)
		(fp_line
			(start -0.12065 -0.2794)
			(end -0.12065 -0.3048)
			(stroke
				(width 0.1)
				(type default)
			)
			(layer "B.Fab")
		)
		(fp_line
			(start -0.120396 0.2794)
			(end 0.12065 0.2794)
			(stroke
				(width 0.1)
				(type default)
			)
			(layer "B.Fab")
		)
		(fp_line
			(start -0.120396 0.3048)
			(end -0.120396 0.2794)
			(stroke
				(width 0.1)
				(type default)
			)
			(layer "B.Fab")
		)
		(fp_line
			(start 0.12065 -0.305054)
			(end 0.12065 -0.2794)
			(stroke
				(width 0.1)
				(type default)
			)
			(layer "B.Fab")
		)
		(fp_line
			(start 0.12065 -0.2794)
			(end -0.12065 -0.2794)
			(stroke
				(width 0.1)
				(type default)
			)
			(layer "B.Fab")
		)
		(fp_line
			(start 0.12065 0.2794)
			(end 0.12065 0.3048)
			(stroke
				(width 0.1)
				(type default)
			)
			(layer "B.Fab")
		)
		(fp_line
			(start 0.12065 0.3048)
			(end 0.67945 0.3048)
			(stroke
				(width 0.1)
				(type default)
			)
			(layer "B.Fab")
		)
		(fp_line
			(start 0.67945 -0.305054)
			(end 0.12065 -0.305054)
			(stroke
				(width 0.1)
				(type default)
			)
			(layer "B.Fab")
		)
		(fp_line
			(start 0.67945 0.3048)
			(end 0.67945 -0.305054)
			(stroke
				(width 0.1)
				(type default)
			)
			(layer "B.Fab")
		)
		(pad "1" smd circle
			(at 0.40005 0 180)
			(size 0 0)
			(layers "B.Cu" "B.Mask" "B.Paste")
			(net "PVDDCR_CPU1_P1")
		)
		(pad "2" smd circle
			(at -0.40005 0 180)
			(size 0 0)
			(layers "B.Cu" "B.Mask" "B.Paste")
			(net "GND")
		)
	)
	(footprint ""
		(layer "B.Cu")
		(at 428.98695 -34.737548 180)
		(property "Reference" "R1356"
			(at 0 0 0)
			(layer "B.SilkS")
			(hide yes)
			(effects
				(font
					(size 1.27 1.27)
				)
				(justify mirror)
			)
		)
		(property "Value" ""
			(at 0 0 0)
			(layer "B.Fab")
			(effects
				(font
					(size 1.27 1.27)
				)
				(justify mirror)
			)
		)
		(duplicate_pad_numbers_are_jumpers no)
		(fp_line
			(start 0.7874 0.4064)
			(end 0.7874 -0.4064)
			(stroke
				(width 0.1524)
				(type default)
			)
			(layer "B.SilkS")
		)
		(fp_line
			(start 0.7874 -0.4064)
			(end -0.7874 -0.4064)
			(stroke
				(width 0.1524)
				(type default)
			)
			(layer "B.SilkS")
		)
		(fp_line
			(start -0.7874 0.4064)
			(end 0.7874 0.4064)
			(stroke
				(width 0.1524)
				(type default)
			)
			(layer "B.SilkS")
		)
		(fp_line
			(start -0.7874 -0.4064)
			(end -0.7874 0.4064)
			(stroke
				(width 0.1524)
				(type default)
			)
			(layer "B.SilkS")
		)
		(fp_line
			(start 0.67945 0.3048)
			(end 0.67945 -0.305054)
			(stroke
				(width 0.1)
				(type default)
			)
			(layer "B.Fab")
		)
		(fp_line
			(start 0.67945 -0.305054)
			(end 0.12065 -0.305054)
			(stroke
				(width 0.1)
				(type default)
			)
			(layer "B.Fab")
		)
		(fp_line
			(start 0.12065 0.3048)
			(end 0.67945 0.3048)
			(stroke
				(width 0.1)
				(type default)
			)
			(layer "B.Fab")
		)
		(fp_line
			(start 0.12065 0.2794)
			(end 0.12065 0.3048)
			(stroke
				(width 0.1)
				(type default)
			)
			(layer "B.Fab")
		)
		(fp_line
			(start 0.12065 -0.2794)
			(end -0.12065 -0.2794)
			(stroke
				(width 0.1)
				(type default)
			)
			(layer "B.Fab")
		)
		(fp_line
			(start 0.12065 -0.305054)
			(end 0.12065 -0.2794)
			(stroke
				(width 0.1)
				(type default)
			)
			(layer "B.Fab")
		)
		(fp_line
			(start -0.120396 0.3048)
			(end -0.120396 0.2794)
			(stroke
				(width 0.1)
				(type default)
			)
			(layer "B.Fab")
		)
		(fp_line
			(start -0.120396 0.2794)
			(end 0.12065 0.2794)
			(stroke
				(width 0.1)
				(type default)
			)
			(layer "B.Fab")
		)
		(fp_line
			(start -0.12065 -0.2794)
			(end -0.12065 -0.3048)
			(stroke
				(width 0.1)
				(type default)
			)
			(layer "B.Fab")
		)
		(fp_line
			(start -0.12065 -0.3048)
			(end -0.67945 -0.3048)
			(stroke
				(width 0.1)
				(type default)
			)
			(layer "B.Fab")
		)
		(fp_line
			(start -0.67945 0.3048)
			(end -0.120396 0.3048)
			(stroke
				(width 0.1)
				(type default)
			)
			(layer "B.Fab")
		)
		(fp_line
			(start -0.67945 -0.3048)
			(end -0.67945 0.3048)
			(stroke
				(width 0.1)
				(type default)
			)
			(layer "B.Fab")
		)
		(pad "1" smd circle
			(at 0.40005 0)
			(size 0 0)
			(layers "B.Cu" "B.Mask" "B.Paste")
			(net "P3V3_AUX")
		)
		(pad "2" smd circle
			(at -0.40005 0)
			(size 0 0)
			(layers "B.Cu" "B.Mask" "B.Paste")
			(net "FM_PRSNT_CPU0_N")
		)
	)
	(footprint ""
		(layer "B.Cu")
		(at 77.6224 -174.960534 90)
		(property "Reference" "PR204"
			(at 0 0 90)
			(layer "B.SilkS")
			(hide yes)
			(effects
				(font
					(size 1.27 1.27)
				)
				(justify mirror)
			)
		)
		(property "Value" ""
			(at 0 0 90)
			(layer "B.Fab")
			(effects
				(font
					(size 1.27 1.27)
				)
				(justify mirror)
			)
		)
		(duplicate_pad_numbers_are_jumpers no)
		(fp_line
			(start 0.7874 -0.4064)
			(end -0.7874 -0.4064)
			(stroke
				(width 0.1524)
				(type default)
			)
			(layer "B.SilkS")
		)
		(fp_line
			(start -0.7874 -0.4064)
			(end -0.7874 0.4064)
			(stroke
				(width 0.1524)
				(type default)
			)
			(layer "B.SilkS")
		)
		(fp_line
			(start 0.7874 0.4064)
			(end 0.7874 -0.4064)
			(stroke
				(width 0.1524)
				(type default)
			)
			(layer "B.SilkS")
		)
		(fp_line
			(start -0.7874 0.4064)
			(end 0.7874 0.4064)
			(stroke
				(width 0.1524)
				(type default)
			)
			(layer "B.SilkS")
		)
		(fp_line
			(start 0.67945 -0.305054)
			(end 0.12065 -0.305054)
			(stroke
				(width 0.1)
				(type default)
			)
			(layer "B.Fab")
		)
		(fp_line
			(start 0.12065 -0.305054)
			(end 0.12065 -0.2794)
			(stroke
				(width 0.1)
				(type default)
			)
			(layer "B.Fab")
		)
		(fp_line
			(start -0.12065 -0.3048)
			(end -0.67945 -0.3048)
			(stroke
				(width 0.1)
				(type default)
			)
			(layer "B.Fab")
		)
		(fp_line
			(start -0.67945 -0.3048)
			(end -0.67945 0.3048)
			(stroke
				(width 0.1)
				(type default)
			)
			(layer "B.Fab")
		)
		(fp_line
			(start 0.12065 -0.2794)
			(end -0.12065 -0.2794)
			(stroke
				(width 0.1)
				(type default)
			)
			(layer "B.Fab")
		)
		(fp_line
			(start -0.12065 -0.2794)
			(end -0.12065 -0.3048)
			(stroke
				(width 0.1)
				(type default)
			)
			(layer "B.Fab")
		)
		(fp_line
			(start 0.12065 0.2794)
			(end 0.12065 0.3048)
			(stroke
				(width 0.1)
				(type default)
			)
			(layer "B.Fab")
		)
		(fp_line
			(start -0.120396 0.2794)
			(end 0.12065 0.2794)
			(stroke
				(width 0.1)
				(type default)
			)
			(layer "B.Fab")
		)
		(fp_line
			(start 0.67945 0.3048)
			(end 0.67945 -0.305054)
			(stroke
				(width 0.1)
				(type default)
			)
			(layer "B.Fab")
		)
		(fp_line
			(start 0.12065 0.3048)
			(end 0.67945 0.3048)
			(stroke
				(width 0.1)
				(type default)
			)
			(layer "B.Fab")
		)
		(fp_line
			(start -0.120396 0.3048)
			(end -0.120396 0.2794)
			(stroke
				(width 0.1)
				(type default)
			)
			(layer "B.Fab")
		)
		(fp_line
			(start -0.67945 0.3048)
			(end -0.120396 0.3048)
			(stroke
				(width 0.1)
				(type default)
			)
			(layer "B.Fab")
		)
		(pad "1" smd circle
			(at 0.40005 0 270)
			(size 0 0)
			(layers "B.Cu" "B.Mask" "B.Paste")
			(net "PVDDCR_CPU0_P1_VOS5")
		)
		(pad "2" smd circle
			(at -0.40005 0 270)
			(size 0 0)
			(layers "B.Cu" "B.Mask" "B.Paste")
			(net "PVDDCR_CPU0_P1")
		)
	)
	(footprint ""
		(layer "B.Cu")
		(at 147.032726 -408.517344 90)
		(property "Reference" "C6746"
			(at 0 0 90)
			(layer "B.SilkS")
			(hide yes)
			(effects
				(font
					(size 1.27 1.27)
				)
				(justify mirror)
			)
		)
		(property "Value" ""
			(at 0 0 90)
			(layer "B.Fab")
			(effects
				(font
					(size 1.27 1.27)
				)
				(justify mirror)
			)
		)
		(duplicate_pad_numbers_are_jumpers no)
		(fp_line
			(start 0.299974 -0.150114)
			(end -0.299974 -0.150114)
			(stroke
				(width 0.1)
				(type default)
			)
			(layer "B.Fab")
		)
		(fp_line
			(start -0.299974 -0.150114)
			(end -0.299974 0.150114)
			(stroke
				(width 0.1)
				(type default)
			)
			(layer "B.Fab")
		)
		(fp_line
			(start 0.299974 0.150114)
			(end 0.299974 -0.150114)
			(stroke
				(width 0.1)
				(type default)
			)
			(layer "B.Fab")
		)
		(fp_line
			(start -0.299974 0.150114)
			(end 0.299974 0.150114)
			(stroke
				(width 0.1)
				(type default)
			)
			(layer "B.Fab")
		)
		(pad "1" smd rect
			(at 0.2667 0 270)
			(size 0.3048 0.381)
			(layers "B.Cu" "B.Mask" "B.Paste")
			(net "P5E_CPU1_P3_TX_BUF_C_DN<10>")
		)
		(pad "2" smd rect
			(at -0.2667 0 270)
			(size 0.3048 0.381)
			(layers "B.Cu" "B.Mask" "B.Paste")
			(net "P5E_CPU1_P3_TX_BUF_DN<10>")
		)
	)
	(footprint ""
		(layer "B.Cu")
		(at 174.98568 -24.653748)
		(property "Reference" "PC2240"
			(at 0 0 0)
			(layer "B.SilkS")
			(hide yes)
			(effects
				(font
					(size 1.27 1.27)
				)
				(justify mirror)
			)
		)
		(property "Value" ""
			(at 0 0 0)
			(layer "B.Fab")
			(effects
				(font
					(size 1.27 1.27)
				)
				(justify mirror)
			)
		)
		(duplicate_pad_numbers_are_jumpers no)
		(fp_line
			(start -1.524 -0.762)
			(end -1.524 0.762)
			(stroke
				(width 0.1524)
				(type default)
			)
			(layer "B.SilkS")
		)
		(fp_line
			(start -1.524 0.762)
			(end 1.524 0.762)
			(stroke
				(width 0.1524)
				(type default)
			)
			(layer "B.SilkS")
		)
		(fp_line
			(start 1.524 -0.762)
			(end -1.524 -0.762)
			(stroke
				(width 0.1524)
				(type default)
			)
			(layer "B.SilkS")
		)
		(fp_line
			(start 1.524 0.762)
			(end 1.524 -0.762)
			(stroke
				(width 0.1524)
				(type default)
			)
			(layer "B.SilkS")
		)
		(fp_line
			(start -1.1049 -0.724916)
			(end 1.1049 -0.724916)
			(stroke
				(width 0.1)
				(type default)
			)
			(layer "B.Fab")
		)
		(fp_line
			(start -1.1049 0.724916)
			(end -1.1049 -0.724916)
			(stroke
				(width 0.1)
				(type default)
			)
			(layer "B.Fab")
		)
		(fp_line
			(start 1.1049 -0.724916)
			(end 1.1049 0.724916)
			(stroke
				(width 0.1)
				(type default)
			)
			(layer "B.Fab")
		)
		(fp_line
			(start 1.1049 0.724916)
			(end -1.1049 0.724916)
			(stroke
				(width 0.1)
				(type default)
			)
			(layer "B.Fab")
		)
		(pad "1" smd rect
			(at 0.889 0)
			(size 1.016 1.27)
			(layers "B.Cu" "B.Mask" "B.Paste")
			(net "P12V_SCM_R")
		)
		(pad "2" smd rect
			(at -0.889 0)
			(size 1.016 1.27)
			(layers "B.Cu" "B.Mask" "B.Paste")
			(net "GND")
		)
	)
)
